(kicad_pcb
	(version 20260206)
	(generator "pcbnew")
	(generator_version "10.0")
	(general
		(thickness 1.21888)
		(legacy_teardrops no)
	)
	(paper "A4")
	(title_block
		(title "timecard-v8 — TimeCard-DC-V8_EXP.PcbDoc")
		(comment 1 "Time Appliance Project (Time Card) / footprints 97-106 of 288")
	)
	(layers
		(0 "F.Cu" signal "TOP")
		(4 "In1.Cu" signal "SGND")
		(6 "In2.Cu" signal "IN1")
		(8 "In3.Cu" signal "IN2")
		(10 "In4.Cu" signal "SGND1")
		(2 "B.Cu" signal "BOTTOM")
		(9 "F.Adhes" user "F.Adhesive")
		(11 "B.Adhes" user "B.Adhesive")
		(13 "F.Paste" user "Top Paste")
		(15 "B.Paste" user "Bottom Paste")
		(5 "F.SilkS" user "Top Overlay")
		(7 "B.SilkS" user "Bottom Overlay")
		(1 "F.Mask" user "Top Solder")
		(3 "B.Mask" user "Bottom Solder")
		(17 "Dwgs.User" user "User.Drawings")
		(19 "Cmts.User" user "User.Comments")
		(21 "Eco1.User" user "User.Eco1")
		(23 "Eco2.User" user "User.Eco2")
		(25 "Edge.Cuts" user)
		(27 "Margin" user)
		(31 "F.CrtYd" user "Top Courtyard")
		(29 "B.CrtYd" user "Bottom Courtyard")
		(35 "F.Fab" user "Top Component Center")
		(33 "B.Fab" user "Bottom Component Center")
	)
	(footprint "Passives:SOT65P210X110-3N"
		(layer "F.Cu")
		(at 224.9261 137.6162 -90)
		(property "Reference" "D8"
			(at -2.006655 0.6 0)
			(unlocked yes)
			(layer "F.SilkS")
			(effects
				(font
					(size 0.762 0.762)
					(thickness 0.2286)
				)
				(justify left bottom)
			)
		)
		(property "Value" "BAT54SW"
			(at 7.401445 -2.7501 0)
			(unlocked yes)
			(layer "F.SilkS")
			(hide yes)
			(effects
				(font
					(size 0.762 0.762)
					(thickness 0.2286)
				)
				(justify left bottom)
			)
		)
		(sheetname "PCIe_JTAG")
		(sheetfile "PCIe_JTAG.kicad_sch")
		(duplicate_pad_numbers_are_jumpers no)
		(fp_line
			(start 0.675 1.1)
			(end -0.325 1.1)
			(stroke
				(width 0.2)
				(type solid)
			)
			(layer "F.SilkS")
		)
		(fp_line
			(start 0.675 1.1)
			(end 0.675 0.65)
			(stroke
				(width 0.2)
				(type solid)
			)
			(layer "F.SilkS")
		)
		(fp_line
			(start 0.675 -0.65)
			(end 0.675 -1.1)
			(stroke
				(width 0.2)
				(type solid)
			)
			(layer "F.SilkS")
		)
		(fp_line
			(start 0.675 -1.1)
			(end -0.325 -1.1)
			(stroke
				(width 0.2)
				(type solid)
			)
			(layer "F.SilkS")
		)
		(fp_circle
			(center -1.125 -1.45)
			(end -1.25 -1.45)
			(stroke
				(width 0.25)
				(type solid)
			)
			(fill no)
			(layer "F.SilkS")
		)
		(pad "1" smd rect
			(at -1.125 -0.65)
			(size 0.5 0.9)
			(layers "F.Cu" "F.Mask" "F.Paste")
			(net "GND")
		)
		(pad "2" smd rect
			(at -1.125 0.65)
			(size 0.5 0.9)
			(layers "F.Cu" "F.Mask" "F.Paste")
			(net "+3.3V")
		)
		(pad "3" smd rect
			(at 1.125 0)
			(size 0.5 0.9)
			(layers "F.Cu" "F.Mask" "F.Paste")
			(net "FPGA_TDI")
		)
	)
	(footprint "SA53:SolderSocket"
		(layer "F.Cu")
		(at 139.9261 94.9162 90)
		(property "Reference" "SKT7"
			(at -2.726921 7.1286 0)
			(unlocked yes)
			(layer "F.SilkS")
			(effects
				(font
					(size 0.762 0.762)
					(thickness 0.2286)
				)
			)
		)
		(property "Value" "0332-0-43-80-18-27-10-0"
			(at -2.910071 16.1362 0)
			(unlocked yes)
			(layer "F.SilkS")
			(hide yes)
			(effects
				(font
					(size 0.762 0.762)
					(thickness 0.2286)
				)
			)
		)
		(sheetname "MAC")
		(sheetfile "MAC.kicad_sch")
		(duplicate_pad_numbers_are_jumpers no)
		(pad "1" thru_hole circle
			(at 0 0 90)
			(size 2.54 2.54)
			(drill 2.0066)
			(layers "*.Cu" "*.Mask")
			(remove_unused_layers no)
			(net "MAC_VCC")
			(thermal_bridge_angle 90)
		)
	)
	(footprint "Vault:CAPC1608X87X45ML20T05"
		(layer "F.Cu")
		(at 194.1761 83.5786 180)
		(property "Reference" "C30"
			(at -0.5786 2.235469 0)
			(unlocked yes)
			(layer "F.SilkS")
			(effects
				(font
					(size 0.762 0.762)
					(thickness 0.2286)
				)
			)
		)
		(property "Value" "0.1uF"
			(at 2.069035 2.630671 180)
			(unlocked yes)
			(layer "F.SilkS")
			(hide yes)
			(effects
				(font
					(size 0.762 0.762)
					(thickness 0.2286)
				)
			)
		)
		(sheetname "GPS_IMU_SENSORS")
		(sheetfile "GPS_IMU_SENSORS.kicad_sch")
		(duplicate_pad_numbers_are_jumpers no)
		(pad "1" smd rect
			(at -0.7 0 270)
			(size 1.1 1.05)
			(layers "F.Cu" "F.Mask" "F.Paste")
			(net "GND")
		)
		(pad "2" smd rect
			(at 0.7 0 270)
			(size 1.1 1.05)
			(layers "F.Cu" "F.Mask" "F.Paste")
			(net "+3.3V")
		)
	)
	(footprint "Vault:RESC1608X55X25NL10T15"
		(layer "F.Cu")
		(at 77.6261 95.1162 180)
		(property "Reference" "R25"
			(at -0.2286 1.223079 0)
			(unlocked yes)
			(layer "F.SilkS")
			(effects
				(font
					(size 0.762 0.762)
					(thickness 0.2286)
				)
			)
		)
		(property "Value" "49.9R"
			(at -2.884671 3.186595 90)
			(unlocked yes)
			(layer "F.SilkS")
			(hide yes)
			(effects
				(font
					(size 0.762 0.762)
					(thickness 0.2286)
				)
			)
		)
		(sheetname "USER_IO")
		(sheetfile "USER_IO.kicad_sch")
		(duplicate_pad_numbers_are_jumpers no)
		(pad "1" smd rect
			(at -0.7 0 270)
			(size 0.9 0.7)
			(layers "F.Cu" "F.Mask" "F.Paste")
			(net "NetR25_1")
		)
		(pad "2" smd rect
			(at 0.7 0 270)
			(size 0.9 0.7)
			(layers "F.Cu" "F.Mask" "F.Paste")
			(net "NetAN1_1")
		)
	)
	(footprint "Vault:RESC1005X40X25LL05T05"
		(layer "F.Cu")
		(at 202.9261 124.9162)
		(property "Reference" "R67"
			(at -3.1714 4.426931 0)
			(unlocked yes)
			(layer "F.SilkS")
			(effects
				(font
					(size 0.762 0.762)
					(thickness 0.2286)
				)
			)
		)
		(property "Value" "4.7K_0402"
			(at -2.389351 6.538405 270)
			(unlocked yes)
			(layer "F.SilkS")
			(hide yes)
			(effects
				(font
					(size 0.762 0.762)
					(thickness 0.2286)
				)
			)
		)
		(sheetname "POWER")
		(sheetfile "POWER.kicad_sch")
		(duplicate_pad_numbers_are_jumpers no)
		(pad "1" smd rect
			(at -0.4 0 90)
			(size 0.45 0.45)
			(layers "F.Cu" "F.Mask" "F.Paste")
			(net "+12V")
		)
		(pad "2" smd rect
			(at 0.4 0 90)
			(size 0.45 0.45)
			(layers "F.Cu" "F.Mask" "F.Paste")
			(net "NetR67_2")
		)
	)
	(footprint "Resistors:RESC1005X04N"
		(layer "F.Cu")
		(at 96.9261 143.3162)
		(property "Reference" "R24"
			(at 1.35111 0.884735 180)
			(unlocked yes)
			(layer "F.SilkS")
			(effects
				(font
					(size 0.762 0.762)
					(thickness 0.2286)
				)
				(justify left bottom)
			)
		)
		(property "Value" "ERJ-2GE0R00X"
			(at -0.2413 3.331845 0)
			(unlocked yes)
			(layer "F.SilkS")
			(hide yes)
			(effects
				(font
					(size 0.762 0.762)
					(thickness 0.2286)
				)
				(justify left bottom)
			)
		)
		(sheetname "PCIe_JTAG")
		(sheetfile "PCIe_JTAG.kicad_sch")
		(duplicate_pad_numbers_are_jumpers no)
		(pad "1" smd rect
			(at -0.425 0 90)
			(size 0.6 0.65)
			(layers "F.Cu" "F.Mask" "F.Paste")
			(net "PRSNT")
		)
		(pad "2" smd rect
			(at 0.425 0 90)
			(size 0.6 0.65)
			(layers "F.Cu" "F.Mask" "F.Paste")
			(net "NetP2_B31")
		)
	)
	(footprint "Miscellaneous Connectors:HDR2X6_CEN"
		(layer "F.Cu")
		(at 212.7461 51.5762 180)
		(property "Reference" "P3"
			(at 18.324329 -2.146705 90)
			(unlocked yes)
			(layer "F.SilkS")
			(effects
				(font
					(size 0.762 0.762)
					(thickness 0.2286)
				)
			)
		)
		(property "Value" "EXT GPIO"
			(at -4.281671 2.296855 90)
			(unlocked yes)
			(layer "F.SilkS")
			(hide yes)
			(effects
				(font
					(size 0.762 0.762)
					(thickness 0.2286)
				)
			)
		)
		(sheetname "GPS_IMU_SENSORS")
		(sheetfile "GPS_IMU_SENSORS.kicad_sch")
		(duplicate_pad_numbers_are_jumpers no)
		(fp_line
			(start 13.97 1.27)
			(end -1.27 1.27)
			(stroke
				(width 0.2)
				(type solid)
			)
			(layer "F.SilkS")
		)
		(fp_line
			(start 13.97 -3.81)
			(end 13.97 1.27)
			(stroke
				(width 0.2)
				(type solid)
			)
			(layer "F.SilkS")
		)
		(fp_line
			(start 13.97 -3.81)
			(end -1.27 -3.81)
			(stroke
				(width 0.2)
				(type solid)
			)
			(layer "F.SilkS")
		)
		(fp_line
			(start -1.27 -3.81)
			(end -1.27 1.27)
			(stroke
				(width 0.2)
				(type solid)
			)
			(layer "F.SilkS")
		)
		(fp_text user "6"
			(at 14.732 0.663575 180)
			(unlocked yes)
			(layer "F.SilkS")
			(effects
				(font
					(size 1.27 1.27)
					(thickness 0.2032)
				)
				(justify left bottom)
			)
		)
		(fp_text user "12"
			(at 14.732 -1.876425 180)
			(unlocked yes)
			(layer "F.SilkS")
			(effects
				(font
					(size 1.27 1.27)
					(thickness 0.2032)
				)
				(justify left bottom)
			)
		)
		(fp_text user "1"
			(at -2.54 0.663575 180)
			(unlocked yes)
			(layer "F.SilkS")
			(effects
				(font
					(size 1.27 1.27)
					(thickness 0.2032)
				)
				(justify left bottom)
			)
		)
		(fp_text user "7"
			(at -2.54 -1.876425 180)
			(unlocked yes)
			(layer "F.SilkS")
			(effects
				(font
					(size 1.27 1.27)
					(thickness 0.2032)
				)
				(justify left bottom)
			)
		)
		(pad "1" thru_hole rect
			(at 0 0 180)
			(size 1.5 1.5)
			(drill 0.9)
			(layers "*.Cu" "*.Mask")
			(remove_unused_layers no)
			(net "EXT_GPIO_1")
		)
		(pad "2" thru_hole circle
			(at 2.54 0 180)
			(size 1.5 1.5)
			(drill 0.9)
			(layers "*.Cu" "*.Mask")
			(remove_unused_layers no)
			(net "EXT_GPIO_2")
			(thermal_bridge_angle 90)
		)
		(pad "3" thru_hole circle
			(at 5.08 0 180)
			(size 1.5 1.5)
			(drill 0.9)
			(layers "*.Cu" "*.Mask")
			(remove_unused_layers no)
			(net "EXT_GPIO_3")
			(thermal_bridge_angle 90)
		)
		(pad "4" thru_hole circle
			(at 7.62 0 180)
			(size 1.5 1.5)
			(drill 0.9)
			(layers "*.Cu" "*.Mask")
			(remove_unused_layers no)
			(net "EXT_GPIO_4")
			(thermal_bridge_angle 90)
		)
		(pad "5" thru_hole circle
			(at 10.16 0 180)
			(size 1.5 1.5)
			(drill 0.9)
			(layers "*.Cu" "*.Mask")
			(remove_unused_layers no)
			(net "GND")
			(thermal_bridge_angle 90)
		)
		(pad "6" thru_hole circle
			(at 12.7 0 180)
			(size 1.5 1.5)
			(drill 0.9)
			(layers "*.Cu" "*.Mask")
			(remove_unused_layers no)
			(net "+3.3V")
			(thermal_bridge_angle 90)
		)
		(pad "7" thru_hole circle
			(at 0 -2.54 180)
			(size 1.5 1.5)
			(drill 0.9)
			(layers "*.Cu" "*.Mask")
			(remove_unused_layers no)
			(net "EXT_GPIO_7")
			(thermal_bridge_angle 90)
		)
		(pad "8" thru_hole circle
			(at 2.54 -2.54 180)
			(size 1.5 1.5)
			(drill 0.9)
			(layers "*.Cu" "*.Mask")
			(remove_unused_layers no)
			(net "EXT_GPIO_8")
			(thermal_bridge_angle 90)
		)
		(pad "9" thru_hole circle
			(at 5.08 -2.54 180)
			(size 1.5 1.5)
			(drill 0.9)
			(layers "*.Cu" "*.Mask")
			(remove_unused_layers no)
			(net "EXT_GPIO_9")
			(thermal_bridge_angle 90)
		)
		(pad "10" thru_hole circle
			(at 7.62 -2.54 180)
			(size 1.5 1.5)
			(drill 0.9)
			(layers "*.Cu" "*.Mask")
			(remove_unused_layers no)
			(net "EXT_GPIO_10")
			(thermal_bridge_angle 90)
		)
		(pad "11" thru_hole circle
			(at 10.16 -2.54 180)
			(size 1.5 1.5)
			(drill 0.9)
			(layers "*.Cu" "*.Mask")
			(remove_unused_layers no)
			(net "GND")
			(thermal_bridge_angle 90)
		)
		(pad "12" thru_hole circle
			(at 12.7 -2.54 180)
			(size 1.5 1.5)
			(drill 0.9)
			(layers "*.Cu" "*.Mask")
			(remove_unused_layers no)
			(net "+3.3V")
			(thermal_bridge_angle 90)
		)
	)
	(footprint "Vault:FP-GRM31C-0_2-e0_3_0_8-IPC_C"
		(layer "F.Cu")
		(at 214.5261 103.0162 90)
		(property "Reference" "C11"
			(at 3.8 -0.493345 270)
			(unlocked yes)
			(layer "F.SilkS")
			(effects
				(font
					(size 0.762 0.762)
					(thickness 0.2286)
				)
				(justify left bottom)
			)
		)
		(property "Value" "4.7uF_50V_1206"
			(at -23.717045 -0.1957 0)
			(unlocked yes)
			(layer "F.SilkS")
			(hide yes)
			(effects
				(font
					(size 0.762 0.762)
					(thickness 0.2286)
				)
				(justify left bottom)
			)
		)
		(sheetname "POWER")
		(sheetfile "POWER.kicad_sch")
		(duplicate_pad_numbers_are_jumpers no)
		(fp_line
			(start -0.39847 -0.9)
			(end 0.39846 -0.9)
			(stroke
				(width 0.2)
				(type solid)
			)
			(layer "F.SilkS")
		)
		(fp_line
			(start -0.39847 0.9)
			(end 0.39846 0.9)
			(stroke
				(width 0.2)
				(type solid)
			)
			(layer "F.SilkS")
		)
		(fp_line
			(start 1.9531 -1)
			(end 1.9531 1)
			(stroke
				(width 0.2)
				(type solid)
			)
			(layer "F.CrtYd")
		)
		(fp_line
			(start -1.9531 -1)
			(end 1.9531 -1)
			(stroke
				(width 0.2)
				(type solid)
			)
			(layer "F.CrtYd")
		)
		(fp_line
			(start -1.9531 -1)
			(end -1.9531 1)
			(stroke
				(width 0.2)
				(type solid)
			)
			(layer "F.CrtYd")
		)
		(fp_line
			(start -1.9531 1)
			(end 1.9531 1)
			(stroke
				(width 0.2)
				(type solid)
			)
			(layer "F.CrtYd")
		)
		(fp_line
			(start 1.9531 -1)
			(end 1.9531 1)
			(stroke
				(width 0.2)
				(type solid)
			)
			(layer "F.Fab")
		)
		(fp_line
			(start -1.9531 -1)
			(end 1.9531 -1)
			(stroke
				(width 0.2)
				(type solid)
			)
			(layer "F.Fab")
		)
		(fp_line
			(start -1.9531 -1)
			(end -1.9531 1)
			(stroke
				(width 0.2)
				(type solid)
			)
			(layer "F.Fab")
		)
		(fp_line
			(start 0 -0.5)
			(end 0 0.5)
			(stroke
				(width 0.1)
				(type solid)
			)
			(layer "F.Fab")
		)
		(fp_line
			(start -0.5 0)
			(end 0.5 0)
			(stroke
				(width 0.1)
				(type solid)
			)
			(layer "F.Fab")
		)
		(fp_line
			(start -1.9531 1)
			(end 1.9531 1)
			(stroke
				(width 0.2)
				(type solid)
			)
			(layer "F.Fab")
		)
		(fp_text user "${REFERENCE}"
			(at -0.00001 0.09602 90)
			(unlocked yes)
			(layer "F.Fab")
			(effects
				(font
					(face "Arial")
					(size 0.63 0.63)
					(thickness 0.1)
				)
				(justify left bottom)
			)
		)
		(pad "1" smd rect
			(at -1.27578 0 90)
			(size 1.15464 1.7062)
			(layers "F.Cu" "F.Mask" "F.Paste")
			(net "+12V")
			(solder_mask_margin 0)
			(solder_paste_margin 0)
		)
		(pad "2" smd rect
			(at 1.27578 0 90)
			(size 1.15464 1.7062)
			(layers "F.Cu" "F.Mask" "F.Paste")
			(net "GND")
			(solder_mask_margin 0)
			(solder_paste_margin 0)
		)
	)
	(footprint "Vault:CAPC1608X87X45ML20T05"
		(layer "F.Cu")
		(at 80.3761 139.6162 -90)
		(property "Reference" "C29"
			(at 2.7714 -0.026931 90)
			(unlocked yes)
			(layer "F.SilkS")
			(effects
				(font
					(size 0.762 0.762)
					(thickness 0.2286)
				)
			)
		)
		(property "Value" "0.1uF"
			(at 2.069035 2.630671 270)
			(unlocked yes)
			(layer "F.SilkS")
			(hide yes)
			(effects
				(font
					(size 0.762 0.762)
					(thickness 0.2286)
				)
			)
		)
		(sheetname "USER_IO")
		(sheetfile "USER_IO.kicad_sch")
		(duplicate_pad_numbers_are_jumpers no)
		(pad "1" smd rect
			(at -0.7 0)
			(size 1.1 1.05)
			(layers "F.Cu" "F.Mask" "F.Paste")
			(net "+3.3V")
		)
		(pad "2" smd rect
			(at 0.7 0)
			(size 1.1 1.05)
			(layers "F.Cu" "F.Mask" "F.Paste")
			(net "GND")
		)
	)
	(footprint "Vault:RESC1005X40X25NL05T10"
		(layer "F.Cu")
		(at 215.3261 113.5162 90)
		(property "Reference" "R60"
			(at 2.423929 2.04404 0)
			(unlocked yes)
			(layer "F.SilkS")
			(effects
				(font
					(size 0.762 0.762)
					(thickness 0.2286)
				)
			)
		)
		(property "Value" "19.6K_1%_0402"
			(at -2.732271 9.40766 0)
			(unlocked yes)
			(layer "F.SilkS")
			(hide yes)
			(effects
				(font
					(size 0.762 0.762)
					(thickness 0.2286)
				)
			)
		)
		(sheetname "POWER")
		(sheetfile "POWER.kicad_sch")
		(duplicate_pad_numbers_are_jumpers no)
		(pad "1" smd rect
			(at -0.425 0 180)
			(size 0.55 0.6)
			(layers "F.Cu" "F.Mask" "F.Paste")
			(net "NetC9_1")
		)
		(pad "2" smd rect
			(at 0.425 0 180)
			(size 0.55 0.6)
			(layers "F.Cu" "F.Mask" "F.Paste")
			(net "NetL1_1")
		)
	)
)
